(kicad_pcb
	(version 20260206)
	(generator "pcbnew")
	(generator_version "10.0")
	(general
		(thickness 1.6)
		(legacy_teardrops no)
	)
	(paper "A4")
	(title_block
		(title "Bryce Canyon_R.DPB_16317-1_OCP.brd")
		(comment 1 "Bryce Canyon / footprints 595-602 of 2099")
	)
	(layers
		(0 "F.Cu" signal "TOP")
		(4 "In1.Cu" signal "L2GND")
		(6 "In2.Cu" signal "L3")
		(8 "In3.Cu" signal "L4VCC")
		(10 "In4.Cu" signal "L5VCC")
		(12 "In5.Cu" signal "L6")
		(14 "In6.Cu" signal "L7GND")
		(2 "B.Cu" signal "BOTTOM")
		(9 "F.Adhes" user "F.Adhesive")
		(11 "B.Adhes" user "B.Adhesive")
		(13 "F.Paste" user "Package Geometry/Pastemask Top")
		(15 "B.Paste" user "Package Geometry/Pastemask Bottom")
		(5 "F.SilkS" user "Ref Des/Silkscreen Top")
		(7 "B.SilkS" user "Ref Des/Silkscreen Bottom")
		(1 "F.Mask" user "Board Geometry/Soldermask Top")
		(3 "B.Mask" user "Board Geometry/Soldermask Bottom")
		(17 "Dwgs.User" user "User.Drawings")
		(19 "Cmts.User" user "User.Comments")
		(21 "Eco1.User" user "User.Eco1")
		(23 "Eco2.User" user "User.Eco2")
		(25 "Edge.Cuts" user "Board Geometry/Outline")
		(27 "Margin" user)
		(31 "F.CrtYd" user "Package Geometry/Place Bound Top")
		(29 "B.CrtYd" user "Package Geometry/Place Bound Bottom")
		(35 "F.Fab" user "Ref Des/Assembly Top")
		(33 "B.Fab" user "Ref Des/Assembly Bottom")
	)
	(footprint ""
		(layer "F.Cu")
		(at 95.563436 -129.66065 90)
		(property "Reference" "C211"
			(at 0 0 90)
			(layer "F.SilkS")
			(hide yes)
			(effects
				(font
					(size 1.27 1.27)
				)
			)
		)
		(property "Value" "SCD01U16V1KX-GP"
			(at -2.8321 -1.7399 90)
			(unlocked yes)
			(layer "F.Fab")
			(hide yes)
			(effects
				(font
					(size 1.016 1.016)
					(thickness 0.1524)
				)
			)
		)
		(property "Device Type" "C0201H13"
			(at -2.8321 -3.2639 90)
			(unlocked yes)
			(layer "F.Fab")
			(hide yes)
			(effects
				(font
					(size 1.016 1.016)
					(thickness 0.1524)
				)
			)
		)
		(duplicate_pad_numbers_are_jumpers no)
		(fp_rect
			(start -0.2794 0.6477)
			(end 0.2794 -0.6477)
			(stroke
				(width 0)
				(type default)
			)
			(fill no)
			(layer "F.CrtYd")
		)
		(fp_rect
			(start -0.2794 0.6477)
			(end 0.2794 -0.6477)
			(stroke
				(width 0)
				(type default)
			)
			(fill no)
			(layer "F.Fab")
		)
		(pad "1" smd custom
			(at 0 -0.2794 90)
			(size 0.0762 0.0762)
			(layers "F.Cu" "F.Mask" "F.Paste")
			(net "SAS_HDD_RX_P14")
			(options
				(clearance outline)
				(anchor circle)
			)
			(primitives
				(gr_poly
					(pts
						(arc
							(start 0.1524 -0.127)
							(mid 0.137521 -0.162921)
							(end 0.1016 -0.1778)
						)
						(arc
							(start -0.1016 -0.1778)
							(mid -0.137521 -0.162921)
							(end -0.1524 -0.127)
						)
						(arc
							(start -0.1524 0.127)
							(mid -0.137521 0.162921)
							(end -0.1016 0.1778)
						)
						(arc
							(start 0.1016 0.1778)
							(mid 0.137521 0.162921)
							(end 0.1524 0.127)
						)
					)
					(width 0)
					(fill yes)
				)
			)
		)
		(pad "2" smd custom
			(at 0 0.2794 90)
			(size 0.0762 0.0762)
			(layers "F.Cu" "F.Mask" "F.Paste")
			(net "PHY_SCC_B_TO_DRV_B_14_DP")
			(options
				(clearance outline)
				(anchor circle)
			)
			(primitives
				(gr_poly
					(pts
						(arc
							(start 0.1524 -0.127)
							(mid 0.137521 -0.162921)
							(end 0.1016 -0.1778)
						)
						(arc
							(start -0.1016 -0.1778)
							(mid -0.137521 -0.162921)
							(end -0.1524 -0.127)
						)
						(arc
							(start -0.1524 0.127)
							(mid -0.137521 0.162921)
							(end -0.1016 0.1778)
						)
						(arc
							(start 0.1016 0.1778)
							(mid 0.137521 0.162921)
							(end 0.1524 0.127)
						)
					)
					(width 0)
					(fill yes)
				)
			)
		)
	)
	(footprint ""
		(layer "F.Cu")
		(at 441.162186 -120.321578 -90)
		(property "Reference" "R1157"
			(at 0 0 270)
			(layer "F.SilkS")
			(hide yes)
			(effects
				(font
					(size 1.27 1.27)
				)
			)
		)
		(property "Value" "10KR2F-2-GP"
			(at 0.064008 -3.993896 270)
			(unlocked yes)
			(layer "F.Fab")
			(hide yes)
			(effects
				(font
					(size 1.016 1.016)
					(thickness 0.1524)
				)
			)
		)
		(property "Device Type" "R402H16"
			(at 0.064008 -5.517896 270)
			(unlocked yes)
			(layer "F.Fab")
			(hide yes)
			(effects
				(font
					(size 1.016 1.016)
					(thickness 0.1524)
				)
			)
		)
		(duplicate_pad_numbers_are_jumpers no)
		(fp_line
			(start -0.508 -0.9398)
			(end -0.508 0.9398)
			(stroke
				(width 0.1524)
				(type default)
			)
			(layer "F.SilkS")
		)
		(fp_line
			(start 0.508 -0.9398)
			(end -0.508 -0.9398)
			(stroke
				(width 0.1524)
				(type default)
			)
			(layer "F.SilkS")
		)
		(fp_rect
			(start -0.508 0.9398)
			(end 0.508 -0.9398)
			(stroke
				(width 0)
				(type default)
			)
			(fill no)
			(layer "F.CrtYd")
		)
		(fp_rect
			(start -0.508 0.9398)
			(end 0.508 -0.9398)
			(stroke
				(width 0)
				(type default)
			)
			(fill no)
			(layer "F.Fab")
		)
		(pad "1" smd custom
			(at 0 -0.4445 270)
			(size 0.1397 0.1397)
			(layers "F.Cu" "F.Mask" "F.Paste")
			(net "P5V_B_4_EN_R")
			(options
				(clearance outline)
				(anchor circle)
			)
			(primitives
				(gr_poly
					(pts
						(arc
							(start -0.1778 -0.2794)
							(mid -0.249642 -0.249642)
							(end -0.2794 -0.1778)
						)
						(arc
							(start -0.2794 0.1778)
							(mid -0.249642 0.249642)
							(end -0.1778 0.2794)
						)
						(arc
							(start 0.1778 0.2794)
							(mid 0.249642 0.249642)
							(end 0.2794 0.1778)
						)
						(arc
							(start 0.2794 -0.1778)
							(mid 0.249642 -0.249642)
							(end 0.1778 -0.2794)
						)
					)
					(width 0)
					(fill yes)
				)
			)
		)
		(pad "2" smd custom
			(at 0 0.4445 270)
			(size 0.1397 0.1397)
			(layers "F.Cu" "F.Mask" "F.Paste")
			(net "GND")
			(options
				(clearance outline)
				(anchor circle)
			)
			(primitives
				(gr_poly
					(pts
						(arc
							(start -0.1778 -0.2794)
							(mid -0.249642 -0.249642)
							(end -0.2794 -0.1778)
						)
						(arc
							(start -0.2794 0.1778)
							(mid -0.249642 0.249642)
							(end -0.1778 0.2794)
						)
						(arc
							(start 0.1778 0.2794)
							(mid 0.249642 0.249642)
							(end 0.2794 0.1778)
						)
						(arc
							(start 0.2794 -0.1778)
							(mid 0.249642 -0.249642)
							(end 0.1778 -0.2794)
						)
					)
					(width 0)
					(fill yes)
				)
			)
		)
	)
	(footprint ""
		(layer "F.Cu")
		(at 261.75081 -224.785174)
		(property "Reference" "R169"
			(at 0 0 0)
			(layer "F.SilkS")
			(hide yes)
			(effects
				(font
					(size 1.27 1.27)
				)
			)
		)
		(property "Value" "10KR2F-2-GP"
			(at 0.064008 -3.993896 0)
			(unlocked yes)
			(layer "F.Fab")
			(hide yes)
			(effects
				(font
					(size 1.016 1.016)
					(thickness 0.1524)
				)
			)
		)
		(property "Device Type" "R402H16"
			(at 0.064008 -5.517896 0)
			(unlocked yes)
			(layer "F.Fab")
			(hide yes)
			(effects
				(font
					(size 1.016 1.016)
					(thickness 0.1524)
				)
			)
		)
		(duplicate_pad_numbers_are_jumpers no)
		(fp_line
			(start -0.508 -0.9398)
			(end -0.508 0.9398)
			(stroke
				(width 0.1524)
				(type default)
			)
			(layer "F.SilkS")
		)
		(fp_line
			(start 0.508 -0.9398)
			(end -0.508 -0.9398)
			(stroke
				(width 0.1524)
				(type default)
			)
			(layer "F.SilkS")
		)
		(fp_rect
			(start -0.508 0.9398)
			(end 0.508 -0.9398)
			(stroke
				(width 0)
				(type default)
			)
			(fill no)
			(layer "F.CrtYd")
		)
		(fp_rect
			(start -0.508 0.9398)
			(end 0.508 -0.9398)
			(stroke
				(width 0)
				(type default)
			)
			(fill no)
			(layer "F.Fab")
		)
		(pad "1" smd custom
			(at 0 -0.4445)
			(size 0.1397 0.1397)
			(layers "F.Cu" "F.Mask" "F.Paste")
			(net "P5V_B_4_SENSE")
			(options
				(clearance outline)
				(anchor circle)
			)
			(primitives
				(gr_poly
					(pts
						(arc
							(start -0.1778 -0.2794)
							(mid -0.249642 -0.249642)
							(end -0.2794 -0.1778)
						)
						(arc
							(start -0.2794 0.1778)
							(mid -0.249642 0.249642)
							(end -0.1778 0.2794)
						)
						(arc
							(start 0.1778 0.2794)
							(mid 0.249642 0.249642)
							(end 0.2794 0.1778)
						)
						(arc
							(start 0.2794 -0.1778)
							(mid 0.249642 -0.249642)
							(end 0.1778 -0.2794)
						)
					)
					(width 0)
					(fill yes)
				)
			)
		)
		(pad "2" smd custom
			(at 0 0.4445)
			(size 0.1397 0.1397)
			(layers "F.Cu" "F.Mask" "F.Paste")
			(net "GND")
			(options
				(clearance outline)
				(anchor circle)
			)
			(primitives
				(gr_poly
					(pts
						(arc
							(start -0.1778 -0.2794)
							(mid -0.249642 -0.249642)
							(end -0.2794 -0.1778)
						)
						(arc
							(start -0.2794 0.1778)
							(mid -0.249642 0.249642)
							(end -0.1778 0.2794)
						)
						(arc
							(start 0.1778 0.2794)
							(mid 0.249642 0.249642)
							(end 0.2794 0.1778)
						)
						(arc
							(start 0.2794 -0.1778)
							(mid 0.249642 -0.249642)
							(end 0.1778 -0.2794)
						)
					)
					(width 0)
					(fill yes)
				)
			)
		)
	)
	(footprint ""
		(layer "F.Cu")
		(at 473.964 -150.622 90)
		(property "Reference" "R600"
			(at 0 0 90)
			(layer "F.SilkS")
			(hide yes)
			(effects
				(font
					(size 1.27 1.27)
				)
			)
		)
		(property "Value" "2R6F-GP"
			(at -0.0508 -4.8514 90)
			(unlocked yes)
			(layer "F.Fab")
			(hide yes)
			(effects
				(font
					(size 1.016 1.016)
					(thickness 0.1524)
				)
			)
		)
		(property "Device Type" "R1206H26"
			(at 0 -6.3754 90)
			(unlocked yes)
			(layer "F.Fab")
			(hide yes)
			(effects
				(font
					(size 1.016 1.016)
					(thickness 0.1524)
				)
			)
		)
		(duplicate_pad_numbers_are_jumpers no)
		(fp_line
			(start 1.016 -2.2352)
			(end 1.016 2.2352)
			(stroke
				(width 0.1524)
				(type default)
			)
			(layer "F.SilkS")
		)
		(fp_line
			(start -1.016 -2.2352)
			(end 1.016 -2.2352)
			(stroke
				(width 0.1524)
				(type default)
			)
			(layer "F.SilkS")
		)
		(fp_line
			(start 1.016 2.2352)
			(end -1.016 2.2352)
			(stroke
				(width 0.1524)
				(type default)
			)
			(layer "F.SilkS")
		)
		(fp_line
			(start -1.016 2.2352)
			(end -1.016 -2.2352)
			(stroke
				(width 0.1524)
				(type default)
			)
			(layer "F.SilkS")
		)
		(fp_rect
			(start -1.0922 2.3114)
			(end 1.0922 -2.3114)
			(stroke
				(width 0)
				(type default)
			)
			(fill no)
			(layer "F.CrtYd")
		)
		(fp_poly
			(pts
				(xy -1.0922 -2.3114) (xy 1.0922 -2.3114) (xy 1.0922 2.3114) (xy -1.0922 2.3114)
			)
			(stroke
				(width 0)
				(type default)
			)
			(fill no)
			(layer "F.Fab")
		)
		(pad "1" smd rect
			(at 0 -1.397 90)
			(size 1.651 1.27)
			(layers "F.Cu" "F.Mask" "F.Paste")
			(net "P12V_HDD23")
		)
		(pad "2" smd rect
			(at 0 1.397 90)
			(size 1.651 1.27)
			(layers "F.Cu" "F.Mask" "F.Paste")
			(net "12V_PRE_23")
		)
	)
	(footprint ""
		(layer "F.Cu")
		(at 161.544 -262.128 90)
		(property "Reference" "C89"
			(at 0 0 90)
			(layer "F.SilkS")
			(hide yes)
			(effects
				(font
					(size 1.27 1.27)
				)
			)
		)
		(property "Value" "SCD01U50V2KX-1GP"
			(at 1.1811 -2.7051 90)
			(unlocked yes)
			(layer "F.Fab")
			(hide yes)
			(effects
				(font
					(size 1.016 1.016)
					(thickness 0.1524)
				)
			)
		)
		(property "Device Type" "C402H22"
			(at 1.1811 -4.2291 90)
			(unlocked yes)
			(layer "F.Fab")
			(hide yes)
			(effects
				(font
					(size 1.016 1.016)
					(thickness 0.1524)
				)
			)
		)
		(duplicate_pad_numbers_are_jumpers no)
		(fp_rect
			(start -0.4318 0.9525)
			(end 0.4318 -0.9525)
			(stroke
				(width 0)
				(type default)
			)
			(fill no)
			(layer "F.CrtYd")
		)
		(fp_rect
			(start -0.4318 0.9525)
			(end 0.4318 -0.9525)
			(stroke
				(width 0)
				(type default)
			)
			(fill no)
			(layer "F.Fab")
		)
		(pad "1" smd custom
			(at 0 -0.4445 90)
			(size 0.1524 0.1524)
			(layers "F.Cu" "F.Mask" "F.Paste")
			(net "HDD_PRSNT_4")
			(options
				(clearance outline)
				(anchor circle)
			)
			(primitives
				(gr_poly
					(pts
						(arc
							(start 0.3048 -0.2032)
							(mid 0.275042 -0.275042)
							(end 0.2032 -0.3048)
						)
						(arc
							(start -0.2032 -0.3048)
							(mid -0.275042 -0.275042)
							(end -0.3048 -0.2032)
						)
						(arc
							(start -0.3048 0.2032)
							(mid -0.275042 0.275042)
							(end -0.2032 0.3048)
						)
						(arc
							(start 0.2032 0.3048)
							(mid 0.275042 0.275042)
							(end 0.3048 0.2032)
						)
					)
					(width 0)
					(fill yes)
				)
			)
		)
		(pad "2" smd custom
			(at 0 0.4445 90)
			(size 0.1524 0.1524)
			(layers "F.Cu" "F.Mask" "F.Paste")
			(net "GND")
			(options
				(clearance outline)
				(anchor circle)
			)
			(primitives
				(gr_poly
					(pts
						(arc
							(start 0.3048 -0.2032)
							(mid 0.275042 -0.275042)
							(end 0.2032 -0.3048)
						)
						(arc
							(start -0.2032 -0.3048)
							(mid -0.275042 -0.275042)
							(end -0.3048 -0.2032)
						)
						(arc
							(start -0.3048 0.2032)
							(mid -0.275042 0.275042)
							(end -0.2032 0.3048)
						)
						(arc
							(start 0.2032 0.3048)
							(mid 0.275042 0.275042)
							(end 0.3048 0.2032)
						)
					)
					(width 0)
					(fill yes)
				)
			)
		)
	)
	(footprint ""
		(layer "F.Cu")
		(at 456.674982 -63.79972)
		(property "Reference" ""
			(at 0 0 0)
			(layer "F.SilkS")
			(hide yes)
			(effects
				(font
					(size 1.27 1.27)
				)
			)
		)
		(property "Value" "*"
			(at -8.398764 -8.057642 0)
			(unlocked yes)
			(layer "F.Fab")
			(hide yes)
			(effects
				(font
					(size 1.016 1.016)
					(thickness 0.1524)
				)
			)
		)
		(duplicate_pad_numbers_are_jumpers no)
		(fp_poly
			(pts
				(arc
					(start 7.3152 0)
					(mid 0 7.3152)
					(end -7.3152 0)
				)
				(arc
					(start -7.3152 -5.9944)
					(mid 0 -13.3096)
					(end 7.3152 -5.9944)
				)
			)
			(stroke
				(width 0)
				(type default)
			)
			(fill no)
			(layer "B.CrtYd")
		)
		(fp_poly
			(pts
				(arc
					(start 7.3152 0)
					(mid 0 7.3152)
					(end -7.3152 0)
				)
				(arc
					(start -7.3152 -5.9944)
					(mid 0 -13.3096)
					(end 7.3152 -5.9944)
				)
			)
			(stroke
				(width 0)
				(type default)
			)
			(fill no)
			(layer "F.CrtYd")
		)
		(fp_poly
			(pts
				(arc
					(start 7.3152 0)
					(mid 0 7.3152)
					(end -7.3152 0)
				)
				(arc
					(start -7.3152 -5.9944)
					(mid 0 -13.3096)
					(end 7.3152 -5.9944)
				)
			)
			(stroke
				(width 0)
				(type default)
			)
			(fill no)
			(layer "B.Fab")
		)
		(fp_poly
			(pts
				(arc
					(start 7.3152 0)
					(mid 0 7.3152)
					(end -7.3152 0)
				)
				(arc
					(start -7.3152 -5.9944)
					(mid 0 -13.3096)
					(end 7.3152 -5.9944)
				)
			)
			(stroke
				(width 0)
				(type default)
			)
			(fill no)
			(layer "F.Fab")
		)
		(pad "1" thru_hole oval
			(at 0 0)
			(size 14.0208 20.0152)
			(drill 0.0254
				(offset 0 -2.9972)
			)
			(layers "*.Cu" "*.Mask")
			(remove_unused_layers no)
			(net "Net_14")
			(clearance -1.002284)
			(thermal_gap 0.1524)
			(padstack
				(mode front_inner_back)
				(layer "Inner"
					(shape custom)
					(size 2.928012 2.928012)
					(options
						(anchor circle)
					)
					(primitives
						(gr_poly
							(pts
								(arc
									(start 4.571746 -2.084324)
									(mid 0.000333 7.430372)
									(end -4.571492 -2.084324)
								)
								(arc
									(start -4.571492 -2.084324)
									(mid -3.570296 -3.611977)
									(end -2.875026 -5.30098)
								)
								(arc
									(start -2.875026 -5.30098)
									(mid 0.000217 -7.43089)
									(end 2.87528 -5.30098)
								)
								(arc
									(start 2.87528 -5.30098)
									(mid 3.570511 -3.611956)
									(end 4.571746 -2.084324)
								)
							)
							(width 0)
							(fill yes)
						)
					)
					(clearance 0.1524)
				)
				(layer "B.Cu"
					(shape oval)
					(size 14.0208 20.0152)
					(offset 0 -2.9972)
					(clearance -1.002284)
				)
			)
		)
		(zone
			(layers "F.Cu" "B.Cu" "In1.Cu" "In2.Cu" "In3.Cu" "In4.Cu" "In5.Cu" "In6.Cu")
			(hatch none 0.5)
			(connect_pads
				(clearance 0)
			)
			(min_thickness 0.25)
			(keepout
				(tracks not_allowed)
				(vias allowed)
				(pads allowed)
				(copperpour not_allowed)
				(footprints allowed)
			)
			(placement
				(enabled no)
				(sheetname "")
			)
			(fill
				(thermal_gap 0.5)
				(thermal_bridge_width 0.5)
				(island_removal_mode 0)
			)
			(polygon
				(pts
					(arc
						(start 449.664582 -69.79412)
						(mid 456.674982 -76.80452)
						(end 463.685382 -69.79412)
					)
					(arc
						(start 463.685382 -63.79972)
						(mid 456.674982 -56.78932)
						(end 449.664582 -63.79972)
					)
				)
			)
		)
	)
	(footprint ""
		(layer "F.Cu")
		(at 320.6496 -261.62 180)
		(property "Reference" "R255"
			(at 0 0 180)
			(layer "F.SilkS")
			(hide yes)
			(effects
				(font
					(size 1.27 1.27)
				)
			)
		)
		(property "Value" "10KR2F-2-GP"
			(at 0.064008 -3.993896 180)
			(unlocked yes)
			(layer "F.Fab")
			(hide yes)
			(effects
				(font
					(size 1.016 1.016)
					(thickness 0.1524)
				)
			)
		)
		(property "Device Type" "R402H16"
			(at 0.064008 -5.517896 180)
			(unlocked yes)
			(layer "F.Fab")
			(hide yes)
			(effects
				(font
					(size 1.016 1.016)
					(thickness 0.1524)
				)
			)
		)
		(duplicate_pad_numbers_are_jumpers no)
		(fp_line
			(start 0.508 -0.9398)
			(end -0.508 -0.9398)
			(stroke
				(width 0.1524)
				(type default)
			)
			(layer "F.SilkS")
		)
		(fp_line
			(start -0.508 -0.9398)
			(end -0.508 0.9398)
			(stroke
				(width 0.1524)
				(type default)
			)
			(layer "F.SilkS")
		)
		(fp_rect
			(start -0.508 0.9398)
			(end 0.508 -0.9398)
			(stroke
				(width 0)
				(type default)
			)
			(fill no)
			(layer "F.CrtYd")
		)
		(fp_rect
			(start -0.508 0.9398)
			(end 0.508 -0.9398)
			(stroke
				(width 0)
				(type default)
			)
			(fill no)
			(layer "F.Fab")
		)
		(pad "1" smd custom
			(at 0 -0.4445 180)
			(size 0.1397 0.1397)
			(layers "F.Cu" "F.Mask" "F.Paste")
			(net "P3V3_STBY_B")
			(options
				(clearance outline)
				(anchor circle)
			)
			(primitives
				(gr_poly
					(pts
						(arc
							(start -0.1778 -0.2794)
							(mid -0.249642 -0.249642)
							(end -0.2794 -0.1778)
						)
						(arc
							(start -0.2794 0.1778)
							(mid -0.249642 0.249642)
							(end -0.1778 0.2794)
						)
						(arc
							(start 0.1778 0.2794)
							(mid 0.249642 0.249642)
							(end 0.2794 0.1778)
						)
						(arc
							(start 0.2794 -0.1778)
							(mid 0.249642 -0.249642)
							(end 0.1778 -0.2794)
						)
					)
					(width 0)
					(fill yes)
				)
			)
		)
		(pad "2" smd custom
			(at 0 0.4445 180)
			(size 0.1397 0.1397)
			(layers "F.Cu" "F.Mask" "F.Paste")
			(net "HDD_PRSNT_6")
			(options
				(clearance outline)
				(anchor circle)
			)
			(primitives
				(gr_poly
					(pts
						(arc
							(start -0.1778 -0.2794)
							(mid -0.249642 -0.249642)
							(end -0.2794 -0.1778)
						)
						(arc
							(start -0.2794 0.1778)
							(mid -0.249642 0.249642)
							(end -0.1778 0.2794)
						)
						(arc
							(start 0.1778 0.2794)
							(mid 0.249642 0.249642)
							(end 0.2794 0.1778)
						)
						(arc
							(start 0.2794 -0.1778)
							(mid 0.249642 -0.249642)
							(end 0.1778 -0.2794)
						)
					)
					(width 0)
					(fill yes)
				)
			)
		)
	)
	(footprint ""
		(layer "F.Cu")
		(at 86.995 -42.291)
		(property "Reference" "C373"
			(at 0 0 0)
			(layer "F.SilkS")
			(hide yes)
			(effects
				(font
					(size 1.27 1.27)
				)
			)
		)
		(property "Value" "SC4D7U25V5KX-1-GP"
			(at -0.0762 -6.1214 0)
			(unlocked yes)
			(layer "F.Fab")
			(hide yes)
			(effects
				(font
					(size 1.016 1.016)
					(thickness 0.1524)
				)
			)
		)
		(property "Device Type" "C805H58"
			(at -0.0762 -8.1534 0)
			(unlocked yes)
			(layer "F.Fab")
			(hide yes)
			(effects
				(font
					(size 1.016 1.016)
					(thickness 0.1524)
				)
			)
		)
		(duplicate_pad_numbers_are_jumpers no)
		(fp_line
			(start 0.635 0)
			(end -0.635 0)
			(stroke
				(width 0.508)
				(type default)
			)
			(layer "F.SilkS")
		)
		(fp_rect
			(start -0.9652 1.778)
			(end 0.9652 -1.778)
			(stroke
				(width 0)
				(type default)
			)
			(fill no)
			(layer "F.CrtYd")
		)
		(fp_poly
			(pts
				(xy -0.9652 -1.778) (xy 0.9652 -1.778) (xy 0.9652 1.778) (xy -0.9652 1.778)
			)
			(stroke
				(width 0)
				(type default)
			)
			(fill no)
			(layer "F.Fab")
		)
		(pad "1" smd rect
			(at 0 -0.9652)
			(size 1.397 1.143)
			(layers "F.Cu" "F.Mask" "F.Paste")
			(net "P12V_HDD26")
		)
		(pad "2" smd rect
			(at 0 0.9652)
			(size 1.397 1.143)
			(layers "F.Cu" "F.Mask" "F.Paste")
			(net "GND")
		)
	)
)
